# T6G (Grand Teton) — schematic netlist excerpt (pin names and nets, part order shuffled) for the footprints in the layout excerpt that follows; sources: Cadence DE-HDL packaged netlist, KiCad conversion of 04192023_DAF0TMB3IC0_F0TG_MB_C_brd_V02_OCP.brd

C2318  Q_CAP  22UF 4V 20% X6S  pkg C0402  page 73 : A = PVDDCR_CPU0_P1 ; B = GND
PR6810  Q_RES  0 5% CHIP  pkg 0402LF  page 362 : A = P0V9_RETIMER_CPU0_SVID_CLK ; B = GND

(kicad_pcb
	(version 20260206)
	(generator "pcbnew")
	(generator_version "10.0")
	(general
		(thickness 1.6)
		(legacy_teardrops no)
	)
	(paper "A4")
	(title_block
		(title "04192023_DAF0TMB3IC0_F0TG_MB_C_brd_V02_OCP.brd")
		(comment 1 "Grand Teton / footprints 6198-6199 of 8354")
	)
	(layers
		(0 "F.Cu" signal "TOP")
		(4 "In1.Cu" signal "GND")
		(6 "In2.Cu" signal "IN1")
		(8 "In3.Cu" signal "GND1")
		(10 "In4.Cu" signal "IN2")
		(12 "In5.Cu" signal "GND2")
		(14 "In6.Cu" signal "IN3")
		(16 "In7.Cu" signal "GND3")
		(18 "In8.Cu" signal "VCC")
		(20 "In9.Cu" signal "VCC1")
		(22 "In10.Cu" signal "GND4")
		(24 "In11.Cu" signal "IN4")
		(26 "In12.Cu" signal "GND5")
		(28 "In13.Cu" signal "IN5")
		(30 "In14.Cu" signal "GND6")
		(32 "In15.Cu" signal "IN6")
		(34 "In16.Cu" signal "GND7")
		(2 "B.Cu" signal "BOTTOM")
		(9 "F.Adhes" user "F.Adhesive")
		(11 "B.Adhes" user "B.Adhesive")
		(13 "F.Paste" user "Package Geometry/Pastemask Top")
		(15 "B.Paste" user "Package Geometry/Pastemask Bottom")
		(5 "F.SilkS" user "Ref Des/Silkscreen Top")
		(7 "B.SilkS" user "Ref Des/Silkscreen Bottom")
		(1 "F.Mask" user "Board Geometry/Soldermask Top")
		(3 "B.Mask" user "Board Geometry/Soldermask Bottom")
		(17 "Dwgs.User" user "User.Drawings")
		(19 "Cmts.User" user "User.Comments")
		(21 "Eco1.User" user "User.Eco1")
		(23 "Eco2.User" user "User.Eco2")
		(25 "Edge.Cuts" user "Board Geometry/Outline")
		(27 "Margin" user)
		(31 "F.CrtYd" user "Package Geometry/Place Bound Top")
		(29 "B.CrtYd" user "Package Geometry/Place Bound Bottom")
		(35 "F.Fab" user "Ref Des/Assembly Top")
		(33 "B.Fab" user "Ref Des/Assembly Bottom")
	)
	(footprint ""
		(layer "B.Cu")
		(at 439.029602 -423.66311)
		(property "Reference" "PR6810"
			(at 0 0 0)
			(layer "B.SilkS")
			(hide yes)
			(effects
				(font
					(size 1.27 1.27)
				)
				(justify mirror)
			)
		)
		(property "Value" ""
			(at 0 0 0)
			(layer "B.Fab")
			(effects
				(font
					(size 1.27 1.27)
				)
				(justify mirror)
			)
		)
		(duplicate_pad_numbers_are_jumpers no)
		(fp_line
			(start -0.7874 -0.4064)
			(end -0.7874 0.4064)
			(stroke
				(width 0.1524)
				(type default)
			)
			(layer "B.SilkS")
		)
		(fp_line
			(start -0.7874 0.4064)
			(end 0.7874 0.4064)
			(stroke
				(width 0.1524)
				(type default)
			)
			(layer "B.SilkS")
		)
		(fp_line
			(start 0.7874 -0.4064)
			(end -0.7874 -0.4064)
			(stroke
				(width 0.1524)
				(type default)
			)
			(layer "B.SilkS")
		)
		(fp_line
			(start 0.7874 0.4064)
			(end 0.7874 -0.4064)
			(stroke
				(width 0.1524)
				(type default)
			)
			(layer "B.SilkS")
		)
		(fp_line
			(start -0.67945 -0.3048)
			(end -0.67945 0.3048)
			(stroke
				(width 0.1)
				(type default)
			)
			(layer "B.Fab")
		)
		(fp_line
			(start -0.67945 0.3048)
			(end -0.120396 0.3048)
			(stroke
				(width 0.1)
				(type default)
			)
			(layer "B.Fab")
		)
		(fp_line
			(start -0.12065 -0.3048)
			(end -0.67945 -0.3048)
			(stroke
				(width 0.1)
				(type default)
			)
			(layer "B.Fab")
		)
		(fp_line
			(start -0.12065 -0.2794)
			(end -0.12065 -0.3048)
			(stroke
				(width 0.1)
				(type default)
			)
			(layer "B.Fab")
		)
		(fp_line
			(start -0.120396 0.2794)
			(end 0.12065 0.2794)
			(stroke
				(width 0.1)
				(type default)
			)
			(layer "B.Fab")
		)
		(fp_line
			(start -0.120396 0.3048)
			(end -0.120396 0.2794)
			(stroke
				(width 0.1)
				(type default)
			)
			(layer "B.Fab")
		)
		(fp_line
			(start 0.12065 -0.305054)
			(end 0.12065 -0.2794)
			(stroke
				(width 0.1)
				(type default)
			)
			(layer "B.Fab")
		)
		(fp_line
			(start 0.12065 -0.2794)
			(end -0.12065 -0.2794)
			(stroke
				(width 0.1)
				(type default)
			)
			(layer "B.Fab")
		)
		(fp_line
			(start 0.12065 0.2794)
			(end 0.12065 0.3048)
			(stroke
				(width 0.1)
				(type default)
			)
			(layer "B.Fab")
		)
		(fp_line
			(start 0.12065 0.3048)
			(end 0.67945 0.3048)
			(stroke
				(width 0.1)
				(type default)
			)
			(layer "B.Fab")
		)
		(fp_line
			(start 0.67945 -0.305054)
			(end 0.12065 -0.305054)
			(stroke
				(width 0.1)
				(type default)
			)
			(layer "B.Fab")
		)
		(fp_line
			(start 0.67945 0.3048)
			(end 0.67945 -0.305054)
			(stroke
				(width 0.1)
				(type default)
			)
			(layer "B.Fab")
		)
		(pad "1" smd circle
			(at 0.40005 0 180)
			(size 0 0)
			(layers "B.Cu" "B.Mask" "B.Paste")
			(net "P0V9_RETIMER_CPU0_SVID_CLK")
		)
		(pad "2" smd circle
			(at -0.40005 0 180)
			(size 0 0)
			(layers "B.Cu" "B.Mask" "B.Paste")
			(net "GND")
		)
	)
	(footprint ""
		(layer "B.Cu")
		(at 122.18289 -245.488206)
		(property "Reference" "C2318"
			(at 0 0 0)
			(layer "B.SilkS")
			(hide yes)
			(effects
				(font
					(size 1.27 1.27)
				)
				(justify mirror)
			)
		)
		(property "Value" ""
			(at 0 0 0)
			(layer "B.Fab")
			(effects
				(font
					(size 1.27 1.27)
				)
				(justify mirror)
			)
		)
		(duplicate_pad_numbers_are_jumpers no)
		(fp_line
			(start -0.7874 -0.4064)
			(end -0.7874 0.4064)
			(stroke
				(width 0.1524)
				(type default)
			)
			(layer "B.SilkS")
		)
		(fp_line
			(start -0.7874 0.4064)
			(end 0.7874 0.4064)
			(stroke
				(width 0.1524)
				(type default)
			)
			(layer "B.SilkS")
		)
		(fp_line
			(start 0.7874 -0.4064)
			(end -0.7874 -0.4064)
			(stroke
				(width 0.1524)
				(type default)
			)
			(layer "B.SilkS")
		)
		(fp_line
			(start 0.7874 0.4064)
			(end 0.7874 -0.4064)
			(stroke
				(width 0.1524)
				(type default)
			)
			(layer "B.SilkS")
		)
		(fp_line
			(start -0.67945 -0.3048)
			(end -0.67945 0.3048)
			(stroke
				(width 0.1)
				(type default)
			)
			(layer "B.Fab")
		)
		(fp_line
			(start -0.67945 0.3048)
			(end -0.120396 0.3048)
			(stroke
				(width 0.1)
				(type default)
			)
			(layer "B.Fab")
		)
		(fp_line
			(start -0.12065 -0.3048)
			(end -0.67945 -0.3048)
			(stroke
				(width 0.1)
				(type default)
			)
			(layer "B.Fab")
		)
		(fp_line
			(start -0.12065 -0.2794)
			(end -0.12065 -0.3048)
			(stroke
				(width 0.1)
				(type default)
			)
			(layer "B.Fab")
		)
		(fp_line
			(start -0.120396 0.2794)
			(end 0.12065 0.2794)
			(stroke
				(width 0.1)
				(type default)
			)
			(layer "B.Fab")
		)
		(fp_line
			(start -0.120396 0.3048)
			(end -0.120396 0.2794)
			(stroke
				(width 0.1)
				(type default)
			)
			(layer "B.Fab")
		)
		(fp_line
			(start 0.12065 -0.305054)
			(end 0.12065 -0.2794)
			(stroke
				(width 0.1)
				(type default)
			)
			(layer "B.Fab")
		)
		(fp_line
			(start 0.12065 -0.2794)
			(end -0.12065 -0.2794)
			(stroke
				(width 0.1)
				(type default)
			)
			(layer "B.Fab")
		)
		(fp_line
			(start 0.12065 0.2794)
			(end 0.12065 0.3048)
			(stroke
				(width 0.1)
				(type default)
			)
			(layer "B.Fab")
		)
		(fp_line
			(start 0.12065 0.3048)
			(end 0.67945 0.3048)
			(stroke
				(width 0.1)
				(type default)
			)
			(layer "B.Fab")
		)
		(fp_line
			(start 0.67945 -0.305054)
			(end 0.12065 -0.305054)
			(stroke
				(width 0.1)
				(type default)
			)
			(layer "B.Fab")
		)
		(fp_line
			(start 0.67945 0.3048)
			(end 0.67945 -0.305054)
			(stroke
				(width 0.1)
				(type default)
			)
			(layer "B.Fab")
		)
		(pad "1" smd circle
			(at 0.40005 0 180)
			(size 0 0)
			(layers "B.Cu" "B.Mask" "B.Paste")
			(net "PVDDCR_CPU0_P1")
		)
		(pad "2" smd circle
			(at -0.40005 0 180)
			(size 0 0)
			(layers "B.Cu" "B.Mask" "B.Paste")
			(net "GND")
		)
	)
)
